(kicad_pcb
	(version 20260206)
	(generator "pcbnew")
	(generator_version "10.0")
	(general
		(thickness 1.6)
		(legacy_teardrops no)
	)
	(paper "A4")
	(title_block
		(title "Wiwynn_Tioga_Pass_MB.brd")
		(comment 1 "Tioga Pass / footprints 2283-2288 of 4770")
	)
	(layers
		(0 "F.Cu" signal "TOP")
		(4 "In1.Cu" signal "L2GND")
		(6 "In2.Cu" signal "L3")
		(8 "In3.Cu" signal "L4GND")
		(10 "In4.Cu" signal "L5")
		(12 "In5.Cu" signal "L6GND")
		(14 "In6.Cu" signal "L7VCC")
		(16 "In7.Cu" signal "L8VCC")
		(18 "In8.Cu" signal "L9GND")
		(20 "In9.Cu" signal "L10")
		(22 "In10.Cu" signal "L11GND")
		(24 "In11.Cu" signal "L12")
		(26 "In12.Cu" signal "L13GND")
		(2 "B.Cu" signal "BOTTOM")
		(9 "F.Adhes" user "F.Adhesive")
		(11 "B.Adhes" user "B.Adhesive")
		(13 "F.Paste" user "Package Geometry/Pastemask Top")
		(15 "B.Paste" user "Package Geometry/Pastemask Bottom")
		(5 "F.SilkS" user "Ref Des/Silkscreen Top")
		(7 "B.SilkS" user "Ref Des/Silkscreen Bottom")
		(1 "F.Mask" user "Board Geometry/Soldermask Top")
		(3 "B.Mask" user "Board Geometry/Soldermask Bottom")
		(17 "Dwgs.User" user "User.Drawings")
		(19 "Cmts.User" user "User.Comments")
		(21 "Eco1.User" user "User.Eco1")
		(23 "Eco2.User" user "User.Eco2")
		(25 "Edge.Cuts" user "Board Geometry/Outline")
		(27 "Margin" user)
		(31 "F.CrtYd" user "Package Geometry/Place Bound Top")
		(29 "B.CrtYd" user "Package Geometry/Place Bound Bottom")
		(35 "F.Fab" user "Ref Des/Assembly Top")
		(33 "B.Fab" user "Ref Des/Assembly Bottom")
	)
	(footprint ""
		(layer "F.Cu")
		(at 164.973 -60.9346 90)
		(property "Reference" "C4E7"
			(at 0.2794 -2.76733 90)
			(unlocked yes)
			(layer "F.SilkS")
			(effects
				(font
					(size 0.7874 0.5842)
					(thickness 0.1524)
				)
			)
		)
		(property "Value" ""
			(at 0 0 90)
			(layer "F.Fab")
			(effects
				(font
					(size 1.27 1.27)
				)
			)
		)
		(duplicate_pad_numbers_are_jumpers no)
		(fp_line
			(start 2.504948 -1.616456)
			(end 2.504948 1.633728)
			(stroke
				(width 0.1524)
				(type default)
			)
			(layer "F.SilkS")
		)
		(fp_line
			(start 1.6002 -1.616456)
			(end 2.504948 -1.616456)
			(stroke
				(width 0.1524)
				(type default)
			)
			(layer "F.SilkS")
		)
		(fp_line
			(start -1.6002 -1.616456)
			(end -2.563114 -1.616456)
			(stroke
				(width 0.1524)
				(type default)
			)
			(layer "F.SilkS")
		)
		(fp_line
			(start -2.563114 -1.616456)
			(end -2.563114 1.633728)
			(stroke
				(width 0.1524)
				(type default)
			)
			(layer "F.SilkS")
		)
		(fp_line
			(start 2.504948 1.633728)
			(end 1.6002 1.633728)
			(stroke
				(width 0.1524)
				(type default)
			)
			(layer "F.SilkS")
		)
		(fp_line
			(start -2.563114 1.633728)
			(end -1.6002 1.633728)
			(stroke
				(width 0.1524)
				(type default)
			)
			(layer "F.SilkS")
		)
		(fp_line
			(start 2.286 7.366)
			(end 2.286 1.63195)
			(stroke
				(width 0.1524)
				(type default)
			)
			(layer "F.SilkS")
		)
		(fp_line
			(start 2.286 7.366)
			(end 1.600708 7.366)
			(stroke
				(width 0.1524)
				(type default)
			)
			(layer "F.SilkS")
		)
		(fp_line
			(start -2.286 7.366)
			(end -2.286 1.632712)
			(stroke
				(width 0.1524)
				(type default)
			)
			(layer "F.SilkS")
		)
		(fp_line
			(start -2.286 7.366)
			(end -1.60147 7.366)
			(stroke
				(width 0.1524)
				(type default)
			)
			(layer "F.SilkS")
		)
		(fp_rect
			(start -2.286 7.366)
			(end 2.286 -0.254)
			(stroke
				(width 0)
				(type default)
			)
			(fill no)
			(layer "F.CrtYd")
		)
		(fp_line
			(start 2.286 -0.254)
			(end 2.286 7.366)
			(stroke
				(width 0.1)
				(type default)
			)
			(layer "F.Fab")
		)
		(fp_line
			(start -2.286 -0.254)
			(end 2.286 -0.254)
			(stroke
				(width 0.1)
				(type default)
			)
			(layer "F.Fab")
		)
		(fp_line
			(start 2.286 7.366)
			(end -2.286 7.366)
			(stroke
				(width 0.1)
				(type default)
			)
			(layer "F.Fab")
		)
		(fp_line
			(start -2.286 7.366)
			(end -2.286 -0.254)
			(stroke
				(width 0.1)
				(type default)
			)
			(layer "F.Fab")
		)
		(pad "1" smd rect
			(at 0 0 90)
			(size 2.54 3.048)
			(layers "F.Cu" "F.Mask" "F.Paste")
			(net "PVCCIO_CPU1")
		)
		(pad "2" smd rect
			(at 0 7.112 90)
			(size 2.54 3.048)
			(layers "F.Cu" "F.Mask" "F.Paste")
			(net "GND")
		)
	)
	(footprint ""
		(layer "F.Cu")
		(at 248.8565 -149.8092 -90)
		(property "Reference" "C5A2"
			(at 1.848866 0.752348 270)
			(unlocked yes)
			(layer "F.SilkS")
			(effects
				(font
					(size 1.27 0.9652)
					(thickness 0.1524)
				)
			)
		)
		(property "Value" ""
			(at 0 0 270)
			(layer "F.Fab")
			(effects
				(font
					(size 1.27 1.27)
				)
			)
		)
		(duplicate_pad_numbers_are_jumpers no)
		(fp_rect
			(start -0.500126 1.598422)
			(end 0.500126 -0.201422)
			(stroke
				(width 0)
				(type default)
			)
			(fill no)
			(layer "F.CrtYd")
		)
		(fp_line
			(start -0.500126 1.598422)
			(end -0.500126 -0.201422)
			(stroke
				(width 0.1)
				(type default)
			)
			(layer "F.Fab")
		)
		(fp_line
			(start 0.500126 1.598422)
			(end -0.500126 1.598422)
			(stroke
				(width 0.1)
				(type default)
			)
			(layer "F.Fab")
		)
		(fp_line
			(start -0.500126 -0.201422)
			(end 0.500126 -0.201422)
			(stroke
				(width 0.1)
				(type default)
			)
			(layer "F.Fab")
		)
		(fp_line
			(start 0.500126 -0.201422)
			(end 0.500126 1.598422)
			(stroke
				(width 0.1)
				(type default)
			)
			(layer "F.Fab")
		)
		(pad "1" smd rect
			(at 0 0 180)
			(size 0.889 0.9906)
			(layers "F.Cu" "F.Mask" "F.Paste")
			(net "PVDDQ_DEF")
		)
		(pad "2" smd rect
			(at 0 1.397 180)
			(size 0.889 0.9906)
			(layers "F.Cu" "F.Mask" "F.Paste")
			(net "GND")
		)
		(zone
			(layer "F.Cu")
			(hatch none 0.5)
			(connect_pads
				(clearance 0)
			)
			(min_thickness 0.25)
			(keepout
				(tracks allowed)
				(vias not_allowed)
				(pads allowed)
				(copperpour not_allowed)
				(footprints allowed)
			)
			(placement
				(enabled no)
				(sheetname "")
			)
			(fill
				(thermal_gap 0.5)
				(thermal_bridge_width 0.5)
				(island_removal_mode 0)
			)
			(polygon
				(pts
					(xy 247.904 -150.3045) (xy 247.904 -149.3139) (xy 248.412 -149.3139) (xy 248.412 -150.3045)
				)
			)
		)
		(zone
			(layer "F.Cu")
			(hatch none 0.5)
			(connect_pads
				(clearance 0)
			)
			(min_thickness 0.25)
			(keepout
				(tracks not_allowed)
				(vias allowed)
				(pads allowed)
				(copperpour not_allowed)
				(footprints allowed)
			)
			(placement
				(enabled no)
				(sheetname "")
			)
			(fill
				(thermal_gap 0.5)
				(thermal_bridge_width 0.5)
				(island_removal_mode 0)
			)
			(polygon
				(pts
					(xy 247.904 -150.3045) (xy 247.904 -149.3139) (xy 248.412 -149.3139) (xy 248.412 -150.3045)
				)
			)
		)
	)
	(footprint ""
		(layer "F.Cu")
		(at 94.308168 -149.778212 90)
		(property "Reference" "C2A8"
			(at 0 0 90)
			(layer "F.SilkS")
			(hide yes)
			(effects
				(font
					(size 1.27 1.27)
				)
			)
		)
		(property "Value" ""
			(at 0 0 90)
			(layer "F.Fab")
			(effects
				(font
					(size 1.27 1.27)
				)
			)
		)
		(duplicate_pad_numbers_are_jumpers no)
		(fp_poly
			(pts
				(xy -0.7239 -0.2159) (xy 0.7239 -0.2159) (xy 0.7239 1.9939) (xy -0.7239 1.9939)
			)
			(stroke
				(width 0)
				(type default)
			)
			(fill no)
			(layer "F.CrtYd")
		)
		(fp_line
			(start 0.7239 -0.2159)
			(end -0.7239 -0.2159)
			(stroke
				(width 0.1)
				(type default)
			)
			(layer "F.Fab")
		)
		(fp_line
			(start -0.7239 -0.2159)
			(end -0.7239 1.9939)
			(stroke
				(width 0.1)
				(type default)
			)
			(layer "F.Fab")
		)
		(fp_line
			(start 0.7239 1.9939)
			(end 0.7239 -0.2159)
			(stroke
				(width 0.1)
				(type default)
			)
			(layer "F.Fab")
		)
		(fp_line
			(start -0.7239 1.9939)
			(end 0.7239 1.9939)
			(stroke
				(width 0.1)
				(type default)
			)
			(layer "F.Fab")
		)
		(pad "1" smd rect
			(at 0 0 90)
			(size 1.27 1.016)
			(layers "F.Cu" "F.Mask" "F.Paste")
			(net "PVDDQ_KLM")
		)
		(pad "2" smd rect
			(at 0 1.778 90)
			(size 1.27 1.016)
			(layers "F.Cu" "F.Mask" "F.Paste")
			(net "GND")
		)
		(zone
			(layer "F.Cu")
			(hatch none 0.5)
			(connect_pads
				(clearance 0)
			)
			(min_thickness 0.25)
			(keepout
				(tracks not_allowed)
				(vias allowed)
				(pads allowed)
				(copperpour not_allowed)
				(footprints allowed)
			)
			(placement
				(enabled no)
				(sheetname "")
			)
			(fill
				(thermal_gap 0.5)
				(thermal_bridge_width 0.5)
				(island_removal_mode 0)
			)
			(polygon
				(pts
					(xy 94.816168 -149.143212) (xy 94.816168 -150.413212) (xy 95.578168 -150.413212) (xy 95.578168 -149.143212)
				)
			)
		)
	)
	(footprint ""
		(layer "F.Cu")
		(at 499.872 -144.399)
		(property "Reference" "DS9A3"
			(at -1.33477 0.11684 90)
			(unlocked yes)
			(layer "F.SilkS")
			(effects
				(font
					(size 0.7874 0.5842)
					(thickness 0.1524)
				)
			)
		)
		(property "Value" ""
			(at 0 0 0)
			(layer "F.Fab")
			(effects
				(font
					(size 1.27 1.27)
				)
			)
		)
		(duplicate_pad_numbers_are_jumpers no)
		(fp_line
			(start -1.826006 1.143254)
			(end -1.345184 0.310388)
			(stroke
				(width 0.1524)
				(type default)
			)
			(layer "F.SilkS")
		)
		(fp_line
			(start -1.345184 -0.813054)
			(end -1.345184 0.310388)
			(stroke
				(width 0.1524)
				(type default)
			)
			(layer "F.SilkS")
		)
		(fp_line
			(start -1.345184 0.310388)
			(end -0.864362 1.143254)
			(stroke
				(width 0.1524)
				(type default)
			)
			(layer "F.SilkS")
		)
		(fp_line
			(start -1.345184 1.143254)
			(end -1.826006 1.143254)
			(stroke
				(width 0.1524)
				(type default)
			)
			(layer "F.SilkS")
		)
		(fp_line
			(start -1.345184 2.05486)
			(end -1.345184 1.143254)
			(stroke
				(width 0.1524)
				(type default)
			)
			(layer "F.SilkS")
		)
		(fp_line
			(start -0.864362 0.310388)
			(end -1.826006 0.310388)
			(stroke
				(width 0.1524)
				(type default)
			)
			(layer "F.SilkS")
		)
		(fp_line
			(start -0.864362 1.143254)
			(end -1.345184 1.143254)
			(stroke
				(width 0.1524)
				(type default)
			)
			(layer "F.SilkS")
		)
		(fp_poly
			(pts
				(xy -0.5715 2.2098) (xy -0.5715 0.2032) (xy 0.5715 0.2032) (xy 0.5715 0.6985)
				(arc
					(start 0.726948 0.6985)
					(mid 1.29058 0.932279)
					(end 1.524 1.49606)
				)
				(arc
					(start 1.524 2.05994)
					(mid 1.2904 2.6239)
					(end 0.72644 2.8575)
				)
				(xy 0.5715 2.8575) (xy 0.5715 3.3528) (xy -0.5715 3.3528)
			)
			(stroke
				(width 0)
				(type default)
			)
			(fill no)
			(layer "F.CrtYd")
		)
		(fp_line
			(start -1.837182 1.132078)
			(end -1.35636 0.299212)
			(stroke
				(width 0.1)
				(type default)
			)
			(layer "F.Fab")
		)
		(fp_line
			(start -1.35636 0.299212)
			(end -1.35636 -0.82423)
			(stroke
				(width 0.1)
				(type default)
			)
			(layer "F.Fab")
		)
		(fp_line
			(start -1.35636 0.299212)
			(end -0.875538 1.132078)
			(stroke
				(width 0.1)
				(type default)
			)
			(layer "F.Fab")
		)
		(fp_line
			(start -1.35636 1.132078)
			(end -1.35636 2.043684)
			(stroke
				(width 0.1)
				(type default)
			)
			(layer "F.Fab")
		)
		(fp_line
			(start -0.875538 0.299212)
			(end -1.837182 0.299212)
			(stroke
				(width 0.1)
				(type default)
			)
			(layer "F.Fab")
		)
		(fp_line
			(start -0.875538 1.132078)
			(end -1.837182 1.132078)
			(stroke
				(width 0.1)
				(type default)
			)
			(layer "F.Fab")
		)
		(fp_line
			(start -0.5715 0.2032)
			(end 0.5715 0.2032)
			(stroke
				(width 0.1)
				(type default)
			)
			(layer "F.Fab")
		)
		(fp_line
			(start -0.5715 0.7112)
			(end 0.5715 0.7112)
			(stroke
				(width 0.1)
				(type default)
			)
			(layer "F.Fab")
		)
		(fp_line
			(start -0.5715 2.8448)
			(end 0.5715 2.8448)
			(stroke
				(width 0.1)
				(type default)
			)
			(layer "F.Fab")
		)
		(fp_line
			(start -0.5715 3.3528)
			(end -0.5715 0.2032)
			(stroke
				(width 0.1)
				(type default)
			)
			(layer "F.Fab")
		)
		(fp_line
			(start 0.5715 0.2032)
			(end 0.5715 3.3528)
			(stroke
				(width 0.1)
				(type default)
			)
			(layer "F.Fab")
		)
		(fp_line
			(start 0.5715 2.8575)
			(end 0.72644 2.8575)
			(stroke
				(width 0.1)
				(type default)
			)
			(layer "F.Fab")
		)
		(fp_line
			(start 0.5715 3.3528)
			(end -0.5715 3.3528)
			(stroke
				(width 0.1)
				(type default)
			)
			(layer "F.Fab")
		)
		(fp_line
			(start 0.72644 0.6985)
			(end 0.5715 0.6985)
			(stroke
				(width 0.1)
				(type default)
			)
			(layer "F.Fab")
		)
		(fp_line
			(start 1.524 2.05994)
			(end 1.524 1.49606)
			(stroke
				(width 0.1)
				(type default)
			)
			(layer "F.Fab")
		)
		(fp_arc
			(start 0.72644 0.6985)
			(mid 1.290388 0.932112)
			(end 1.524 1.49606)
			(stroke
				(width 0.1)
				(type default)
			)
			(layer "F.Fab")
		)
		(fp_arc
			(start 1.524 2.05994)
			(mid 1.290388 2.623888)
			(end 0.72644 2.8575)
			(stroke
				(width 0.1)
				(type default)
			)
			(layer "F.Fab")
		)
		(pad "1" smd rect
			(at 0 0)
			(size 1.524 1.524)
			(layers "F.Cu" "F.Mask" "F.Paste")
			(net "FM_SPEAKER_PCH_N")
		)
		(pad "2" smd rect
			(at 0 3.556)
			(size 1.524 1.524)
			(layers "F.Cu" "F.Mask" "F.Paste")
			(net "FM_BEEP_LED_P")
		)
		(pad "3" smd rect
			(at -0.762 1.778)
			(size 0.889 0.889)
			(layers "F.Cu" "F.Mask" "F.Paste")
			(net "Net_6473")
		)
		(zone
			(layer "F.Cu")
			(hatch none 0.5)
			(connect_pads
				(clearance 0)
			)
			(min_thickness 0.25)
			(keepout
				(tracks allowed)
				(vias not_allowed)
				(pads allowed)
				(copperpour not_allowed)
				(footprints allowed)
			)
			(placement
				(enabled no)
				(sheetname "")
			)
			(fill
				(thermal_gap 0.5)
				(thermal_bridge_width 0.5)
				(island_removal_mode 0)
			)
			(polygon
				(pts
					(xy 500.4435 -143.5862) (xy 500.4435 -141.6558) (xy 499.3005 -141.6558) (xy 499.3005 -143.5862)
				)
			)
		)
	)
	(footprint ""
		(layer "F.Cu")
		(at 321.16522 -120.53316 90)
		(property "Reference" "C6B11"
			(at -0.8382 -0.67818 90)
			(unlocked yes)
			(layer "F.SilkS")
			(effects
				(font
					(size 0.4064 0.254)
					(thickness 0.1524)
				)
				(justify left)
			)
		)
		(property "Value" ""
			(at 0 0 90)
			(layer "F.Fab")
			(effects
				(font
					(size 1.27 1.27)
				)
			)
		)
		(duplicate_pad_numbers_are_jumpers no)
		(fp_poly
			(pts
				(xy 0.3048 -0.1016) (xy 0.3048 0.9906) (xy -0.3048 0.9906) (xy -0.3048 -0.1016)
			)
			(stroke
				(width 0)
				(type default)
			)
			(fill no)
			(layer "F.CrtYd")
		)
		(fp_line
			(start 0.3048 -0.1016)
			(end -0.3048 -0.1016)
			(stroke
				(width 0.1)
				(type default)
			)
			(layer "F.Fab")
		)
		(fp_line
			(start -0.3048 -0.1016)
			(end -0.3048 0.9906)
			(stroke
				(width 0.1)
				(type default)
			)
			(layer "F.Fab")
		)
		(fp_line
			(start 0.3048 0.9906)
			(end 0.3048 -0.1016)
			(stroke
				(width 0.1)
				(type default)
			)
			(layer "F.Fab")
		)
		(fp_line
			(start -0.3048 0.9906)
			(end 0.3048 0.9906)
			(stroke
				(width 0.1)
				(type default)
			)
			(layer "F.Fab")
		)
		(pad "1" smd rect
			(at 0 0 90)
			(size 0.508 0.508)
			(layers "F.Cu" "F.Mask" "F.Paste")
			(net "P3E_CPU0_PE1_PCH_TXN<12>")
		)
		(pad "2" smd rect
			(at 0 0.889 90)
			(size 0.508 0.508)
			(layers "F.Cu" "F.Mask" "F.Paste")
			(net "P3E_CPU0_PE1_PCH_C_TXN<12>")
		)
		(zone
			(layer "F.Cu")
			(hatch none 0.5)
			(connect_pads
				(clearance 0)
			)
			(min_thickness 0.25)
			(keepout
				(tracks allowed)
				(vias not_allowed)
				(pads allowed)
				(copperpour not_allowed)
				(footprints allowed)
			)
			(placement
				(enabled no)
				(sheetname "")
			)
			(fill
				(thermal_gap 0.5)
				(thermal_bridge_width 0.5)
				(island_removal_mode 0)
			)
			(polygon
				(pts
					(xy 321.41922 -120.27916) (xy 321.41922 -120.78716) (xy 321.80022 -120.78716) (xy 321.80022 -120.27916)
				)
			)
		)
		(zone
			(layer "F.Cu")
			(hatch none 0.5)
			(connect_pads
				(clearance 0)
			)
			(min_thickness 0.25)
			(keepout
				(tracks not_allowed)
				(vias allowed)
				(pads allowed)
				(copperpour not_allowed)
				(footprints allowed)
			)
			(placement
				(enabled no)
				(sheetname "")
			)
			(fill
				(thermal_gap 0.5)
				(thermal_bridge_width 0.5)
				(island_removal_mode 0)
			)
			(polygon
				(pts
					(xy 321.80022 -120.27916) (xy 321.80022 -120.78716) (xy 321.41922 -120.78716) (xy 321.41922 -120.27916)
				)
			)
		)
	)
	(footprint ""
		(layer "F.Cu")
		(at 376.3772 -147.8788 -90)
		(property "Reference" "L7A2"
			(at 3.378708 -4.251706 270)
			(unlocked yes)
			(layer "F.SilkS")
			(effects
				(font
					(size 0.4064 0.254)
					(thickness 0.1524)
				)
			)
		)
		(property "Value" ""
			(at 0 0 270)
			(layer "F.Fab")
			(effects
				(font
					(size 1.27 1.27)
				)
			)
		)
		(duplicate_pad_numbers_are_jumpers no)
		(fp_line
			(start -1.1303 3.199892)
			(end -1.1303 1.6637)
			(stroke
				(width 0.1524)
				(type default)
			)
			(layer "F.SilkS")
		)
		(fp_line
			(start 8.3693 3.199892)
			(end -1.1303 3.199892)
			(stroke
				(width 0.1524)
				(type default)
			)
			(layer "F.SilkS")
		)
		(fp_line
			(start 8.3693 1.6637)
			(end 8.3693 3.199892)
			(stroke
				(width 0.1524)
				(type default)
			)
			(layer "F.SilkS")
		)
		(fp_line
			(start -1.1303 -1.6637)
			(end -1.1303 -3.199892)
			(stroke
				(width 0.1524)
				(type default)
			)
			(layer "F.SilkS")
		)
		(fp_line
			(start -1.1303 -3.199892)
			(end 8.3693 -3.199892)
			(stroke
				(width 0.1524)
				(type default)
			)
			(layer "F.SilkS")
		)
		(fp_line
			(start 8.3693 -3.199892)
			(end 8.3693 -1.6637)
			(stroke
				(width 0.1524)
				(type default)
			)
			(layer "F.SilkS")
		)
		(fp_rect
			(start -1.1303 3.199892)
			(end 8.3693 -3.199892)
			(stroke
				(width 0)
				(type default)
			)
			(fill no)
			(layer "F.CrtYd")
		)
		(fp_line
			(start -1.1303 3.199892)
			(end -1.1303 -3.199892)
			(stroke
				(width 0.1)
				(type default)
			)
			(layer "F.Fab")
		)
		(fp_line
			(start 8.3693 3.199892)
			(end -1.1303 3.199892)
			(stroke
				(width 0.1)
				(type default)
			)
			(layer "F.Fab")
		)
		(fp_line
			(start -1.1303 -3.199892)
			(end 8.3693 -3.199892)
			(stroke
				(width 0.1)
				(type default)
			)
			(layer "F.Fab")
		)
		(fp_line
			(start 8.3693 -3.199892)
			(end 8.3693 3.199892)
			(stroke
				(width 0.1)
				(type default)
			)
			(layer "F.Fab")
		)
		(pad "1" smd rect
			(at 0 0 270)
			(size 3.683 2.667)
			(layers "F.Cu" "F.Mask" "F.Paste")
			(net "VR_PVNN_PCH_PH1_PHASE_SW")
		)
		(pad "2" smd rect
			(at 7.239 0 270)
			(size 3.683 2.667)
			(layers "F.Cu" "F.Mask" "F.Paste")
			(net "PVNN_PCH_STBY")
		)
	)
)
